# SCM (Grand Teton) — schematic netlist excerpt (pin names and nets, part order shuffled) for the footprints in the layout excerpt that follows; sources: Cadence DE-HDL packaged netlist, KiCad conversion of 12092022_DA0F0TMDCD0_F0T_Management_Board_D_brd_V3_OCP.brd

R308  Q_RES  0 5% CHIP  pkg 0402LF  page 41 : A = P3V3_AUX ; B = VCCIO3
FS1  Q_FUSE  1.1A/8V EMPTY  pkg SMLF  page 23 : \1\ = CRT_VCC5_2_D ; \2\ = CRT_VCC5_2_FUSE

(kicad_pcb
	(version 20260206)
	(generator "pcbnew")
	(generator_version "10.0")
	(general
		(thickness 1.6)
		(legacy_teardrops no)
	)
	(paper "A4")
	(title_block
		(title "12092022_DA0F0TMDCD0_F0T_Management_Board_D_brd_V3_OCP.brd")
		(comment 1 "Grand Teton / footprints 1137-1138 of 1440")
	)
	(layers
		(0 "F.Cu" signal "TOP")
		(4 "In1.Cu" signal "GND")
		(6 "In2.Cu" signal "IN1")
		(8 "In3.Cu" signal "GND1")
		(10 "In4.Cu" signal "IN2")
		(12 "In5.Cu" signal "VCC")
		(14 "In6.Cu" signal "VCC1")
		(16 "In7.Cu" signal "IN3")
		(18 "In8.Cu" signal "GND2")
		(20 "In9.Cu" signal "IN4")
		(22 "In10.Cu" signal "GND3")
		(2 "B.Cu" signal "BOTTOM")
		(9 "F.Adhes" user "F.Adhesive")
		(11 "B.Adhes" user "B.Adhesive")
		(13 "F.Paste" user "Package Geometry/Pastemask Top")
		(15 "B.Paste" user "Package Geometry/Pastemask Bottom")
		(5 "F.SilkS" user "Ref Des/Silkscreen Top")
		(7 "B.SilkS" user "Ref Des/Silkscreen Bottom")
		(1 "F.Mask" user "Board Geometry/Soldermask Top")
		(3 "B.Mask" user "Board Geometry/Soldermask Bottom")
		(17 "Dwgs.User" user "User.Drawings")
		(19 "Cmts.User" user "User.Comments")
		(21 "Eco1.User" user "User.Eco1")
		(23 "Eco2.User" user "User.Eco2")
		(25 "Edge.Cuts" user "Board Geometry/Outline")
		(27 "Margin" user)
		(31 "F.CrtYd" user "Package Geometry/Place Bound Top")
		(29 "B.CrtYd" user "Package Geometry/Place Bound Bottom")
		(35 "F.Fab" user "Ref Des/Assembly Top")
		(33 "B.Fab" user "Ref Des/Assembly Bottom")
	)
	(footprint ""
		(layer "B.Cu")
		(at 25.7048 -94.8182 -90)
		(property "Reference" "R308"
			(at 0 0 90)
			(layer "B.SilkS")
			(hide yes)
			(effects
				(font
					(size 1.27 1.27)
				)
				(justify mirror)
			)
		)
		(property "Value" ""
			(at 0 0 90)
			(layer "B.Fab")
			(effects
				(font
					(size 1.27 1.27)
				)
				(justify mirror)
			)
		)
		(duplicate_pad_numbers_are_jumpers no)
		(fp_line
			(start -0.7874 0.4064)
			(end 0.7874 0.4064)
			(stroke
				(width 0.1524)
				(type default)
			)
			(layer "B.SilkS")
		)
		(fp_line
			(start 0.7874 0.4064)
			(end 0.7874 -0.4064)
			(stroke
				(width 0.1524)
				(type default)
			)
			(layer "B.SilkS")
		)
		(fp_line
			(start -0.7874 -0.4064)
			(end -0.7874 0.4064)
			(stroke
				(width 0.1524)
				(type default)
			)
			(layer "B.SilkS")
		)
		(fp_line
			(start 0.7874 -0.4064)
			(end -0.7874 -0.4064)
			(stroke
				(width 0.1524)
				(type default)
			)
			(layer "B.SilkS")
		)
		(fp_line
			(start -0.67945 0.3048)
			(end -0.120396 0.3048)
			(stroke
				(width 0.1)
				(type default)
			)
			(layer "B.Fab")
		)
		(fp_line
			(start -0.120396 0.3048)
			(end -0.120396 0.2794)
			(stroke
				(width 0.1)
				(type default)
			)
			(layer "B.Fab")
		)
		(fp_line
			(start 0.12065 0.3048)
			(end 0.67945 0.3048)
			(stroke
				(width 0.1)
				(type default)
			)
			(layer "B.Fab")
		)
		(fp_line
			(start 0.67945 0.3048)
			(end 0.67945 -0.305054)
			(stroke
				(width 0.1)
				(type default)
			)
			(layer "B.Fab")
		)
		(fp_line
			(start -0.120396 0.2794)
			(end 0.12065 0.2794)
			(stroke
				(width 0.1)
				(type default)
			)
			(layer "B.Fab")
		)
		(fp_line
			(start 0.12065 0.2794)
			(end 0.12065 0.3048)
			(stroke
				(width 0.1)
				(type default)
			)
			(layer "B.Fab")
		)
		(fp_line
			(start -0.12065 -0.2794)
			(end -0.12065 -0.3048)
			(stroke
				(width 0.1)
				(type default)
			)
			(layer "B.Fab")
		)
		(fp_line
			(start 0.12065 -0.2794)
			(end -0.12065 -0.2794)
			(stroke
				(width 0.1)
				(type default)
			)
			(layer "B.Fab")
		)
		(fp_line
			(start -0.67945 -0.3048)
			(end -0.67945 0.3048)
			(stroke
				(width 0.1)
				(type default)
			)
			(layer "B.Fab")
		)
		(fp_line
			(start -0.12065 -0.3048)
			(end -0.67945 -0.3048)
			(stroke
				(width 0.1)
				(type default)
			)
			(layer "B.Fab")
		)
		(fp_line
			(start 0.12065 -0.305054)
			(end 0.12065 -0.2794)
			(stroke
				(width 0.1)
				(type default)
			)
			(layer "B.Fab")
		)
		(fp_line
			(start 0.67945 -0.305054)
			(end 0.12065 -0.305054)
			(stroke
				(width 0.1)
				(type default)
			)
			(layer "B.Fab")
		)
		(pad "1" smd circle
			(at 0.40005 0 90)
			(size 0 0)
			(layers "B.Cu" "B.Mask" "B.Paste")
			(net "P3V3_AUX")
		)
		(pad "2" smd circle
			(at -0.40005 0 90)
			(size 0 0)
			(layers "B.Cu" "B.Mask" "B.Paste")
			(net "VCCIO3")
		)
	)
	(footprint ""
		(layer "B.Cu")
		(at 31.7754 -20.5232 90)
		(property "Reference" "FS1"
			(at -4.9022 -1.06807 270)
			(unlocked yes)
			(layer "B.SilkS")
			(effects
				(font
					(size 0.7874 0.5842)
					(thickness 0.1524)
				)
				(justify left mirror)
			)
		)
		(property "Value" ""
			(at 0 0 90)
			(layer "B.Fab")
			(effects
				(font
					(size 1.27 1.27)
				)
				(justify mirror)
			)
		)
		(duplicate_pad_numbers_are_jumpers no)
		(fp_line
			(start 2.100326 -1.100074)
			(end -2.100326 -1.100074)
			(stroke
				(width 0.1524)
				(type default)
			)
			(layer "B.SilkS")
		)
		(fp_line
			(start -2.100326 -1.100074)
			(end -2.100326 1.100074)
			(stroke
				(width 0.1524)
				(type default)
			)
			(layer "B.SilkS")
		)
		(fp_line
			(start 2.100326 1.100074)
			(end 2.100326 -1.100074)
			(stroke
				(width 0.1524)
				(type default)
			)
			(layer "B.SilkS")
		)
		(fp_line
			(start -2.100326 1.100074)
			(end 2.100326 1.100074)
			(stroke
				(width 0.1524)
				(type default)
			)
			(layer "B.SilkS")
		)
		(fp_line
			(start 1.778 -1.100074)
			(end 1.778 -0.9652)
			(stroke
				(width 0.1)
				(type default)
			)
			(layer "B.Fab")
		)
		(fp_line
			(start -1.778 -1.100074)
			(end 1.778 -1.100074)
			(stroke
				(width 0.1)
				(type default)
			)
			(layer "B.Fab")
		)
		(fp_line
			(start 2.011426 -0.9652)
			(end 2.011426 0.9652)
			(stroke
				(width 0.1)
				(type default)
			)
			(layer "B.Fab")
		)
		(fp_line
			(start 2.0066 -0.9652)
			(end 2.011426 -0.9652)
			(stroke
				(width 0.1)
				(type default)
			)
			(layer "B.Fab")
		)
		(fp_line
			(start 1.778 -0.9652)
			(end 2.0066 -0.9652)
			(stroke
				(width 0.1)
				(type default)
			)
			(layer "B.Fab")
		)
		(fp_line
			(start -1.778 -0.9652)
			(end -1.778 -1.100074)
			(stroke
				(width 0.1)
				(type default)
			)
			(layer "B.Fab")
		)
		(fp_line
			(start -2.0066 -0.9652)
			(end -1.778 -0.9652)
			(stroke
				(width 0.1)
				(type default)
			)
			(layer "B.Fab")
		)
		(fp_line
			(start -2.010918 -0.9652)
			(end -2.0066 -0.9652)
			(stroke
				(width 0.1)
				(type default)
			)
			(layer "B.Fab")
		)
		(fp_line
			(start 2.011426 0.9652)
			(end 2.0066 0.9652)
			(stroke
				(width 0.1)
				(type default)
			)
			(layer "B.Fab")
		)
		(fp_line
			(start 2.0066 0.9652)
			(end 1.778 0.9652)
			(stroke
				(width 0.1)
				(type default)
			)
			(layer "B.Fab")
		)
		(fp_line
			(start 1.778 0.9652)
			(end 1.778 1.100074)
			(stroke
				(width 0.1)
				(type default)
			)
			(layer "B.Fab")
		)
		(fp_line
			(start -1.778 0.9652)
			(end -2.0066 0.9652)
			(stroke
				(width 0.1)
				(type default)
			)
			(layer "B.Fab")
		)
		(fp_line
			(start -2.0066 0.9652)
			(end -2.010918 0.9652)
			(stroke
				(width 0.1)
				(type default)
			)
			(layer "B.Fab")
		)
		(fp_line
			(start -2.010918 0.9652)
			(end -2.010918 -0.9652)
			(stroke
				(width 0.1)
				(type default)
			)
			(layer "B.Fab")
		)
		(fp_line
			(start 1.778 1.100074)
			(end -1.778 1.100074)
			(stroke
				(width 0.1)
				(type default)
			)
			(layer "B.Fab")
		)
		(fp_line
			(start -1.778 1.100074)
			(end -1.778 0.9652)
			(stroke
				(width 0.1)
				(type default)
			)
			(layer "B.Fab")
		)
		(pad "1" smd rect
			(at 1.450086 0 270)
			(size 1.016 1.8034)
			(layers "B.Cu" "B.Mask" "B.Paste")
			(net "CRT_VCC5_2_D")
		)
		(pad "2" smd rect
			(at -1.450086 0 270)
			(size 1.016 1.8034)
			(layers "B.Cu" "B.Mask" "B.Paste")
			(net "CRT_VCC5_2_FUSE")
		)
	)
)
